# T6G (Grand Teton) — schematic netlist excerpt (pin names and nets, part order shuffled) for the footprints in the layout excerpt that follows; sources: Cadence DE-HDL packaged netlist, KiCad conversion of 04192023_DAF0TMB3IC0_F0TG_MB_C_brd_V02_OCP.brd

R358  Q_RES  0 5% EMPTY  pkg 0402LF  page 161 : A = SMB_CPU0_CPU1_SEC_SCL_R2 ; B = SMB_CPU1_SEC_R_SCL
PC602_1  Q_CAP  22UF 4V 20% X6S  pkg C0805  page 198 : A = PVDDCR_SOC_P0 ; B = GND
C2474  Q_CAP  22UF 4V 20% X6S  pkg C0402  page 74 : A = PVDDCR_SOC_P1 ; B = GND

(kicad_pcb
	(version 20260206)
	(generator "pcbnew")
	(generator_version "10.0")
	(general
		(thickness 1.6)
		(legacy_teardrops no)
	)
	(paper "A4")
	(title_block
		(title "04192023_DAF0TMB3IC0_F0TG_MB_C_brd_V02_OCP.brd")
		(comment 1 "Grand Teton / footprints 6301-6303 of 8354")
	)
	(layers
		(0 "F.Cu" signal "TOP")
		(4 "In1.Cu" signal "GND")
		(6 "In2.Cu" signal "IN1")
		(8 "In3.Cu" signal "GND1")
		(10 "In4.Cu" signal "IN2")
		(12 "In5.Cu" signal "GND2")
		(14 "In6.Cu" signal "IN3")
		(16 "In7.Cu" signal "GND3")
		(18 "In8.Cu" signal "VCC")
		(20 "In9.Cu" signal "VCC1")
		(22 "In10.Cu" signal "GND4")
		(24 "In11.Cu" signal "IN4")
		(26 "In12.Cu" signal "GND5")
		(28 "In13.Cu" signal "IN5")
		(30 "In14.Cu" signal "GND6")
		(32 "In15.Cu" signal "IN6")
		(34 "In16.Cu" signal "GND7")
		(2 "B.Cu" signal "BOTTOM")
		(9 "F.Adhes" user "F.Adhesive")
		(11 "B.Adhes" user "B.Adhesive")
		(13 "F.Paste" user "Package Geometry/Pastemask Top")
		(15 "B.Paste" user "Package Geometry/Pastemask Bottom")
		(5 "F.SilkS" user "Ref Des/Silkscreen Top")
		(7 "B.SilkS" user "Ref Des/Silkscreen Bottom")
		(1 "F.Mask" user "Board Geometry/Soldermask Top")
		(3 "B.Mask" user "Board Geometry/Soldermask Bottom")
		(17 "Dwgs.User" user "User.Drawings")
		(19 "Cmts.User" user "User.Comments")
		(21 "Eco1.User" user "User.Eco1")
		(23 "Eco2.User" user "User.Eco2")
		(25 "Edge.Cuts" user "Board Geometry/Outline")
		(27 "Margin" user)
		(31 "F.CrtYd" user "Package Geometry/Place Bound Top")
		(29 "B.CrtYd" user "Package Geometry/Place Bound Bottom")
		(35 "F.Fab" user "Ref Des/Assembly Top")
		(33 "B.Fab" user "Ref Des/Assembly Bottom")
	)
	(footprint ""
		(layer "B.Cu")
		(at 237.363 -234.061 -90)
		(property "Reference" "R358"
			(at 0 0 90)
			(layer "B.SilkS")
			(hide yes)
			(effects
				(font
					(size 1.27 1.27)
				)
				(justify mirror)
			)
		)
		(property "Value" ""
			(at 0 0 90)
			(layer "B.Fab")
			(effects
				(font
					(size 1.27 1.27)
				)
				(justify mirror)
			)
		)
		(duplicate_pad_numbers_are_jumpers no)
		(fp_line
			(start -0.7874 0.4064)
			(end 0.7874 0.4064)
			(stroke
				(width 0.1524)
				(type default)
			)
			(layer "B.SilkS")
		)
		(fp_line
			(start 0.7874 0.4064)
			(end 0.7874 -0.4064)
			(stroke
				(width 0.1524)
				(type default)
			)
			(layer "B.SilkS")
		)
		(fp_line
			(start -0.7874 -0.4064)
			(end -0.7874 0.4064)
			(stroke
				(width 0.1524)
				(type default)
			)
			(layer "B.SilkS")
		)
		(fp_line
			(start 0.7874 -0.4064)
			(end -0.7874 -0.4064)
			(stroke
				(width 0.1524)
				(type default)
			)
			(layer "B.SilkS")
		)
		(fp_line
			(start -0.67945 0.3048)
			(end -0.120396 0.3048)
			(stroke
				(width 0.1)
				(type default)
			)
			(layer "B.Fab")
		)
		(fp_line
			(start -0.120396 0.3048)
			(end -0.120396 0.2794)
			(stroke
				(width 0.1)
				(type default)
			)
			(layer "B.Fab")
		)
		(fp_line
			(start 0.12065 0.3048)
			(end 0.67945 0.3048)
			(stroke
				(width 0.1)
				(type default)
			)
			(layer "B.Fab")
		)
		(fp_line
			(start 0.67945 0.3048)
			(end 0.67945 -0.305054)
			(stroke
				(width 0.1)
				(type default)
			)
			(layer "B.Fab")
		)
		(fp_line
			(start -0.120396 0.2794)
			(end 0.12065 0.2794)
			(stroke
				(width 0.1)
				(type default)
			)
			(layer "B.Fab")
		)
		(fp_line
			(start 0.12065 0.2794)
			(end 0.12065 0.3048)
			(stroke
				(width 0.1)
				(type default)
			)
			(layer "B.Fab")
		)
		(fp_line
			(start -0.12065 -0.2794)
			(end -0.12065 -0.3048)
			(stroke
				(width 0.1)
				(type default)
			)
			(layer "B.Fab")
		)
		(fp_line
			(start 0.12065 -0.2794)
			(end -0.12065 -0.2794)
			(stroke
				(width 0.1)
				(type default)
			)
			(layer "B.Fab")
		)
		(fp_line
			(start -0.67945 -0.3048)
			(end -0.67945 0.3048)
			(stroke
				(width 0.1)
				(type default)
			)
			(layer "B.Fab")
		)
		(fp_line
			(start -0.12065 -0.3048)
			(end -0.67945 -0.3048)
			(stroke
				(width 0.1)
				(type default)
			)
			(layer "B.Fab")
		)
		(fp_line
			(start 0.12065 -0.305054)
			(end 0.12065 -0.2794)
			(stroke
				(width 0.1)
				(type default)
			)
			(layer "B.Fab")
		)
		(fp_line
			(start 0.67945 -0.305054)
			(end 0.12065 -0.305054)
			(stroke
				(width 0.1)
				(type default)
			)
			(layer "B.Fab")
		)
		(pad "1" smd circle
			(at 0.40005 0 90)
			(size 0 0)
			(layers "B.Cu" "B.Mask" "B.Paste")
			(net "SMB_CPU0_CPU1_SEC_SCL_R2")
		)
		(pad "2" smd circle
			(at -0.40005 0 90)
			(size 0 0)
			(layers "B.Cu" "B.Mask" "B.Paste")
			(net "SMB_CPU1_SEC_R_SCL")
		)
	)
	(footprint ""
		(layer "B.Cu")
		(at 102.402386 -256.734564 180)
		(property "Reference" "C2474"
			(at 0 0 0)
			(layer "B.SilkS")
			(hide yes)
			(effects
				(font
					(size 1.27 1.27)
				)
				(justify mirror)
			)
		)
		(property "Value" ""
			(at 0 0 0)
			(layer "B.Fab")
			(effects
				(font
					(size 1.27 1.27)
				)
				(justify mirror)
			)
		)
		(duplicate_pad_numbers_are_jumpers no)
		(fp_line
			(start 0.7874 0.4064)
			(end 0.7874 -0.4064)
			(stroke
				(width 0.1524)
				(type default)
			)
			(layer "B.SilkS")
		)
		(fp_line
			(start 0.7874 -0.4064)
			(end -0.7874 -0.4064)
			(stroke
				(width 0.1524)
				(type default)
			)
			(layer "B.SilkS")
		)
		(fp_line
			(start -0.7874 0.4064)
			(end 0.7874 0.4064)
			(stroke
				(width 0.1524)
				(type default)
			)
			(layer "B.SilkS")
		)
		(fp_line
			(start -0.7874 -0.4064)
			(end -0.7874 0.4064)
			(stroke
				(width 0.1524)
				(type default)
			)
			(layer "B.SilkS")
		)
		(fp_line
			(start 0.67945 0.3048)
			(end 0.67945 -0.305054)
			(stroke
				(width 0.1)
				(type default)
			)
			(layer "B.Fab")
		)
		(fp_line
			(start 0.67945 -0.305054)
			(end 0.12065 -0.305054)
			(stroke
				(width 0.1)
				(type default)
			)
			(layer "B.Fab")
		)
		(fp_line
			(start 0.12065 0.3048)
			(end 0.67945 0.3048)
			(stroke
				(width 0.1)
				(type default)
			)
			(layer "B.Fab")
		)
		(fp_line
			(start 0.12065 0.2794)
			(end 0.12065 0.3048)
			(stroke
				(width 0.1)
				(type default)
			)
			(layer "B.Fab")
		)
		(fp_line
			(start 0.12065 -0.2794)
			(end -0.12065 -0.2794)
			(stroke
				(width 0.1)
				(type default)
			)
			(layer "B.Fab")
		)
		(fp_line
			(start 0.12065 -0.305054)
			(end 0.12065 -0.2794)
			(stroke
				(width 0.1)
				(type default)
			)
			(layer "B.Fab")
		)
		(fp_line
			(start -0.120396 0.3048)
			(end -0.120396 0.2794)
			(stroke
				(width 0.1)
				(type default)
			)
			(layer "B.Fab")
		)
		(fp_line
			(start -0.120396 0.2794)
			(end 0.12065 0.2794)
			(stroke
				(width 0.1)
				(type default)
			)
			(layer "B.Fab")
		)
		(fp_line
			(start -0.12065 -0.2794)
			(end -0.12065 -0.3048)
			(stroke
				(width 0.1)
				(type default)
			)
			(layer "B.Fab")
		)
		(fp_line
			(start -0.12065 -0.3048)
			(end -0.67945 -0.3048)
			(stroke
				(width 0.1)
				(type default)
			)
			(layer "B.Fab")
		)
		(fp_line
			(start -0.67945 0.3048)
			(end -0.120396 0.3048)
			(stroke
				(width 0.1)
				(type default)
			)
			(layer "B.Fab")
		)
		(fp_line
			(start -0.67945 -0.3048)
			(end -0.67945 0.3048)
			(stroke
				(width 0.1)
				(type default)
			)
			(layer "B.Fab")
		)
		(pad "1" smd circle
			(at 0.40005 0)
			(size 0 0)
			(layers "B.Cu" "B.Mask" "B.Paste")
			(net "PVDDCR_SOC_P1")
		)
		(pad "2" smd circle
			(at -0.40005 0)
			(size 0 0)
			(layers "B.Cu" "B.Mask" "B.Paste")
			(net "GND")
		)
	)
	(footprint ""
		(layer "B.Cu")
		(at 401.359116 -185.63336 90)
		(property "Reference" "PC602_1"
			(at 0 0 90)
			(layer "B.SilkS")
			(hide yes)
			(effects
				(font
					(size 1.27 1.27)
				)
				(justify mirror)
			)
		)
		(property "Value" ""
			(at 0 0 90)
			(layer "B.Fab")
			(effects
				(font
					(size 1.27 1.27)
				)
				(justify mirror)
			)
		)
		(duplicate_pad_numbers_are_jumpers no)
		(fp_line
			(start 1.524 -0.762)
			(end -1.524 -0.762)
			(stroke
				(width 0.1524)
				(type default)
			)
			(layer "B.SilkS")
		)
		(fp_line
			(start -1.524 -0.762)
			(end -1.524 0.762)
			(stroke
				(width 0.1524)
				(type default)
			)
			(layer "B.SilkS")
		)
		(fp_line
			(start 1.524 0.762)
			(end 1.524 -0.762)
			(stroke
				(width 0.1524)
				(type default)
			)
			(layer "B.SilkS")
		)
		(fp_line
			(start -1.524 0.762)
			(end 1.524 0.762)
			(stroke
				(width 0.1524)
				(type default)
			)
			(layer "B.SilkS")
		)
		(fp_line
			(start 1.1049 -0.724916)
			(end 1.1049 0.724916)
			(stroke
				(width 0.1)
				(type default)
			)
			(layer "B.Fab")
		)
		(fp_line
			(start -1.1049 -0.724916)
			(end 1.1049 -0.724916)
			(stroke
				(width 0.1)
				(type default)
			)
			(layer "B.Fab")
		)
		(fp_line
			(start 1.1049 0.724916)
			(end -1.1049 0.724916)
			(stroke
				(width 0.1)
				(type default)
			)
			(layer "B.Fab")
		)
		(fp_line
			(start -1.1049 0.724916)
			(end -1.1049 -0.724916)
			(stroke
				(width 0.1)
				(type default)
			)
			(layer "B.Fab")
		)
		(pad "1" smd rect
			(at 0.889 0 90)
			(size 1.016 1.27)
			(layers "B.Cu" "B.Mask" "B.Paste")
			(net "PVDDCR_SOC_P0")
		)
		(pad "2" smd rect
			(at -0.889 0 90)
			(size 1.016 1.27)
			(layers "B.Cu" "B.Mask" "B.Paste")
			(net "GND")
		)
	)
)
